FILE_TYPE = CONNECTIVITY;
{Allegro Design Entry HDL 17.4-2019 S026 (4007227) 1/17/2022}
"PAGE_NUMBER" = 25;
0"NC";
1"P5E_CPU0_P3_TX_DN<15:0>";
2"P5E_CPU0_P3_TX_DP<15:0>";
3"P5E_CPU0_P3_RX_DP<15:0>";
4"P5E_CPU0_P3_RX_DN<15:0>";
5"P5E_CPU0_P2_RX_DP<15:0>";
6"P5E_CPU0_P2_RX_DN<15:0>";
7"P5E_CPU0_P2_TX_DN<15:0>";
8"P5E_CPU0_P2_TX_DP<15:0>";
9"P5E_CPU0_P2_RX_DN<2>";
10"P5E_CPU0_P2_RX_DP<3>";
11"P5E_CPU0_P2_TX_DN<4>";
12"P5E_CPU0_P2_TX_DP<4>";
13"P5E_CPU0_P3_TX_DN<9>";
14"P5E_CPU0_P3_TX_DP<9>";
15"P5E_CPU0_P3_TX_DN<8>";
16"P5E_CPU0_P3_TX_DN<7>";
17"P5E_CPU0_P3_TX_DP<1>";
18"P5E_CPU0_P3_TX_DN<0>";
19"P5E_CPU0_P3_RX_DN<2>";
20"P5E_CPU0_P3_RX_DP<3>";
21"P5E_CPU0_P3_RX_DP<2>";
22"P5E_CPU0_P2_RX_DN<13>";
23"P5E_CPU0_P2_RX_DP<13>";
24"P5E_CPU0_P2_RX_DN<12>";
25"P5E_CPU0_P2_RX_DN<7>";
26"P5E_CPU0_P2_RX_DN<6>";
27"P5E_CPU0_P2_RX_DN<5>";
28"P5E_CPU0_P2_RX_DP<7>";
29"P5E_CPU0_P2_RX_DN<4>";
30"P5E_CPU0_P2_RX_DP<6>";
31"P5E_CPU0_P2_RX_DN<3>";
32"P5E_CPU0_P2_RX_DP<5>";
33"P5E_CPU0_P2_RX_DP<4>";
34"P5E_CPU0_P2_RX_DN<1>";
35"P5E_CPU0_P2_RX_DN<0>";
36"P5E_CPU0_P2_RX_DP<2>";
37"P5E_CPU0_P2_RX_DP<1>";
38"P5E_CPU0_P2_RX_DP<0>";
39"P5E_CPU0_P2_RX_DN<14>";
40"P5E_CPU0_P2_RX_DP<12>";
41"P5E_CPU0_P2_RX_DN<11>";
42"P5E_CPU0_P2_RX_DP<11>";
43"P5E_CPU0_P2_RX_DN<10>";
44"P5E_CPU0_P2_RX_DP<10>";
45"P5E_CPU0_P2_RX_DN<9>";
46"P5E_CPU0_P2_RX_DP<9>";
47"P5E_CPU0_P2_RX_DN<8>";
48"P5E_CPU0_P2_RX_DP<8>";
49"P5E_CPU0_P2_TX_DN<7>";
50"P5E_CPU0_P2_TX_DN<6>";
51"P5E_CPU0_P2_TX_DN<5>";
52"P5E_CPU0_P2_TX_DP<7>";
53"P5E_CPU0_P2_TX_DP<6>";
54"P5E_CPU0_P2_TX_DN<3>";
55"P5E_CPU0_P2_TX_DP<5>";
56"P5E_CPU0_P2_TX_DN<2>";
57"P5E_CPU0_P2_TX_DN<1>";
58"P5E_CPU0_P2_TX_DP<3>";
59"P5E_CPU0_P2_TX_DN<0>";
60"P5E_CPU0_P2_TX_DP<2>";
61"P5E_CPU0_P2_TX_DP<1>";
62"P5E_CPU0_P2_TX_DP<0>";
63"P5E_CPU0_P2_TX_DP<15>";
64"P5E_CPU0_P2_TX_DN<14>";
65"P5E_CPU0_P2_TX_DP<14>";
66"P5E_CPU0_P2_TX_DN<13>";
67"P5E_CPU0_P2_TX_DP<13>";
68"P5E_CPU0_P2_TX_DN<12>";
69"P5E_CPU0_P2_TX_DP<12>";
70"P5E_CPU0_P2_TX_DN<11>";
71"P5E_CPU0_P2_TX_DP<11>";
72"P5E_CPU0_P2_TX_DN<10>";
73"P5E_CPU0_P2_TX_DP<10>";
74"P5E_CPU0_P2_TX_DN<9>";
75"P5E_CPU0_P2_TX_DP<9>";
76"P5E_CPU0_P2_TX_DN<8>";
77"P5E_CPU0_P2_TX_DP<8>";
78"P5E_CPU0_P2_TX_DN<15>";
79"P5E_CPU0_P2_RX_DN<15>";
80"P5E_CPU0_P2_RX_DP<14>";
81"P5E_CPU0_P3_TX_DN<11>";
82"P5E_CPU0_P3_TX_DP<11>";
83"P5E_CPU0_P3_TX_DP<10>";
84"P5E_CPU0_P3_TX_DN<5>";
85"P5E_CPU0_P3_TX_DP<5>";
86"P5E_CPU0_P3_RX_DN<15>";
87"P5E_CPU0_P3_RX_DP<15>";
88"P5E_CPU0_P3_RX_DP<14>";
89"P5E_CPU0_P3_RX_DN<13>";
90"P5E_CPU0_P3_RX_DP<13>";
91"P5E_CPU0_P3_RX_DP<12>";
92"P5E_CPU0_P3_RX_DP<10>";
93"P5E_CPU0_P3_RX_DP<9>";
94"P5E_CPU0_P3_RX_DP<8>";
95"P5E_CPU0_P3_RX_DN<7>";
96"P5E_CPU0_P3_RX_DP<6>";
97"P5E_CPU0_P3_RX_DN<5>";
98"P5E_CPU0_P3_RX_DP<5>";
99"P5E_CPU0_P3_RX_DN<1>";
100"P5E_CPU0_P3_RX_DP<0>";
101"P5E_CPU0_P3_RX_DN<4>";
102"P5E_CPU0_P3_RX_DP<4>";
103"P5E_CPU0_P3_RX_DN<6>";
104"P5E_CPU0_P3_RX_DP<7>";
105"P5E_CPU0_P3_RX_DN<8>";
106"P5E_CPU0_P3_RX_DN<9>";
107"P5E_CPU0_P3_RX_DN<10>";
108"P5E_CPU0_P3_RX_DN<11>";
109"P5E_CPU0_P3_TX_DP<12>";
110"P5E_CPU0_P3_TX_DN<10>";
111"P5E_CPU0_P3_RX_DP<11>";
112"P5E_CPU0_P3_RX_DN<12>";
113"P5E_CPU0_P3_RX_DN<14>";
114"P5E_CPU0_P3_TX_DN<15>";
115"P5E_CPU0_P3_TX_DP<15>";
116"P5E_CPU0_P3_TX_DN<14>";
117"P5E_CPU0_P3_TX_DP<14>";
118"P5E_CPU0_P3_TX_DN<13>";
119"P5E_CPU0_P3_TX_DP<13>";
120"P5E_CPU0_P3_TX_DN<12>";
121"P5E_CPU0_P3_TX_DN<6>";
122"P5E_CPU0_P3_TX_DP<6>";
123"P5E_CPU0_P3_RX_DN<3>";
124"P5E_CPU0_P2_RX_DP<15>";
125"P5E_CPU0_P3_TX_DP<8>";
126"P5E_CPU0_P3_TX_DP<7>";
127"P5E_CPU0_P3_TX_DP<0>";
128"P5E_CPU0_P3_TX_DN<1>";
129"P5E_CPU0_P3_TX_DP<3>";
130"P5E_CPU0_P3_TX_DN<3>";
131"P5E_CPU0_P3_TX_DP<4>";
132"P5E_CPU0_P3_TX_DN<4>";
133"P5E_CPU0_P3_RX_DN<0>";
134"P5E_CPU0_P3_RX_DP<1>";
135"P5E_CPU0_P3_TX_DP<2>";
136"P5E_CPU0_P3_TX_DN<2>";
%"GENOA_SP5"
"17","(-5025,5075)","0","pure_quanta","I147";
;
LOCATION"U25"
$SEC"17"
CDS_SEC"17"
VALUE"SOCKET6096_13568-001"
MATERIAL"IO"
PART_TYPE"SMLF"
CDS_LMAN_SYM_OUTLINE"-600,950,600,-950"
NEEDS_NO_SIZE"TRUE"
CDS_LIB"pure_quanta"
PART_NUMBER"DGA^6000030";
"P2_RXN7"
$PN"CU30"25;
"P2_RXN6"
$PN"CN30"26;
"P2_RXN5"
$PN"CR33"27;
"P2_RXP7"
$PN"CU29"28;
"P2_TXN7"
$PN"BU29"49;
"P2_RXN4"
$PN"CU33"29;
"P2_RXP6"
$PN"CN29"30;
"P2_TXN6"
$PN"BW32"50;
"P2_RXN3"
$PN"CN33"31;
"P2_RXP5"
$PN"CR32"32;
"P2_TXN5"
$PN"CA32"51;
"P2_TXP7"
$PN"BU30"52;
"P2_RXN2"
$PN"CT36"9;
"P2_RXP4"
$PN"CU32"33;
"P2_TXN4"
$PN"BU32"11;
"P2_TXP6"
$PN"BW33"53;
"P2_RXN1"
$PN"CP36"34;
"P2_RXP3"
$PN"CN32"10;
"P2_TXN3"
$PN"BY35"54;
"P2_TXP5"
$PN"CA33"55;
"P2_RXN0"
$PN"CM36"35;
"P2_RXP2"
$PN"CT35"36;
"P2_TXN2"
$PN"CB35"56;
"P2_TXP4"
$PN"BU33"12;
"P2_RXP1"
$PN"CP35"37;
"P2_TXN1"
$PN"BV35"57;
"P2_TXP3"
$PN"BY36"58;
"P2_RXP0"
$PN"CM35"38;
"P2_TXN0"
$PN"BT35"59;
"P2_TXP2"
$PN"CB36"60;
"P2_TXP1"
$PN"BV36"61;
"P2_TXP0"
$PN"BT36"62;
"P2_TXN15"
$PN"BW23"78;
"P2_TXP15"
$PN"BW24"63;
"P2_TXN14"
$PN"CA23"64;
"P2_TXP14"
$PN"CA24"65;
"P2_TXN13"
$PN"BU23"66;
"P2_TXP13"
$PN"BU24"67;
"P2_TXN12"
$PN"BW26"68;
"P2_TXP12"
$PN"BW27"69;
"P2_TXN11"
$PN"CA26"70;
"P2_TXP11"
$PN"CA27"71;
"P2_TXN10"
$PN"BU26"72;
"P2_TXP10"
$PN"BU27"73;
"P2_TXN9"
$PN"BW29"74;
"P2_TXP9"
$PN"BW30"75;
"P2_TXN8"
$PN"CA29"76;
"P2_TXP8"
$PN"CA30"77;
"P2_RXN15"
$PN"CN24"79;
"P2_RXP15"
$PN"CN23"124;
"P2_RXN14"
$PN"CR24"39;
"P2_RXP14"
$PN"CR23"80;
"P2_RXN13"
$PN"CL24"22;
"P2_RXP13"
$PN"CL23"23;
"P2_RXN12"
$PN"CN27"24;
"P2_RXP12"
$PN"CN26"40;
"P2_RXN11"
$PN"CR27"41;
"P2_RXP11"
$PN"CR26"42;
"P2_RXN10"
$PN"CU27"43;
"P2_RXP10"
$PN"CU26"44;
"P2_RXN9"
$PN"CL27"45;
"P2_RXP9"
$PN"CL26"46;
"P2_RXN8"
$PN"CR30"47;
"P2_RXP8"
$PN"CR29"48;
%"GENOA_SP5"
"18","(-5025,2250)","0","pure_quanta","I148";
;
LOCATION"U25"
$SEC"18"
CDS_SEC"18"
PART_TYPE"SMLF"
MATERIAL"IO"
VALUE"SOCKET6096_13568-001"
CDS_LMAN_SYM_OUTLINE"-600,950,600,-950"
NEEDS_NO_SIZE"TRUE"
CDS_LIB"pure_quanta"
PART_NUMBER"DGA^6000030";
"P3_TXN15"
$PN"CE23"114;
"P3_TXP15"
$PN"CE24"115;
"P3_TXN14"
$PN"CG23"116;
"P3_TXP14"
$PN"CG24"117;
"P3_TXN13"
$PN"CC23"118;
"P3_TXP13"
$PN"CC24"119;
"P3_TXN12"
$PN"CE26"120;
"P3_TXP12"
$PN"CE27"109;
"P3_TXN11"
$PN"CG26"81;
"P3_TXP11"
$PN"CG27"82;
"P3_TXN10"
$PN"CC26"110;
"P3_TXP10"
$PN"CC27"83;
"P3_TXN9"
$PN"CE29"13;
"P3_TXP9"
$PN"CE30"14;
"P3_TXN8"
$PN"CG29"15;
"P3_TXP8"
$PN"CG30"125;
"P3_TXN7"
$PN"CC29"16;
"P3_TXP7"
$PN"CC30"126;
"P3_TXN6"
$PN"CE32"121;
"P3_TXP6"
$PN"CE33"122;
"P3_TXN5"
$PN"CG32"84;
"P3_TXP5"
$PN"CG33"85;
"P3_TXN4"
$PN"CJ32"132;
"P3_TXP4"
$PN"CJ33"131;
"P3_TXN3"
$PN"CC32"130;
"P3_TXP3"
$PN"CC33"129;
"P3_TXN2"
$PN"CH35"136;
"P3_TXP2"
$PN"CH36"135;
"P3_TXN1"
$PN"CF35"128;
"P3_TXP1"
$PN"CF36"17;
"P3_TXN0"
$PN"CD35"18;
"P3_TXP0"
$PN"CD36"127;
"P3_RXN15"
$PN"CU24"86;
"P3_RXP15"
$PN"CU23"87;
"P3_RXN14"
$PN"DA24"113;
"P3_RXP14"
$PN"DA23"88;
"P3_RXN13"
$PN"DC24"89;
"P3_RXP13"
$PN"DC23"90;
"P3_RXN12"
$PN"CW24"112;
"P3_RXP12"
$PN"CW23"91;
"P3_RXN11"
$PN"DA27"108;
"P3_RXP11"
$PN"DA26"111;
"P3_RXN10"
$PN"DC27"107;
"P3_RXP10"
$PN"DC26"92;
"P3_RXN9"
$PN"CW27"106;
"P3_RXP9"
$PN"CW26"93;
"P3_RXN8"
$PN"DA30"105;
"P3_RXP8"
$PN"DA29"94;
"P3_RXN7"
$PN"DC30"95;
"P3_RXP7"
$PN"DC29"104;
"P3_RXN6"
$PN"CW30"103;
"P3_RXP6"
$PN"CW29"96;
"P3_RXN5"
$PN"DA33"97;
"P3_RXP5"
$PN"DA32"98;
"P3_RXN4"
$PN"DC33"101;
"P3_RXP4"
$PN"DC32"102;
"P3_RXN3"
$PN"CW33"123;
"P3_RXP3"
$PN"CW32"20;
"P3_RXN2"
$PN"DB36"19;
"P3_RXP2"
$PN"DB35"21;
"P3_RXN1"
$PN"CY36"99;
"P3_RXP1"
$PN"CY35"134;
"P3_RXN0"
$PN"CV36"133;
"P3_RXP0"
$PN"CV35"100;
%"TAP"
"6","(-3700,5725)","2","mstr_standard","I151";
;
BOM_COST"IO_SLOT"
ROOM"RISER1"
CDS_LIB"mstr_standard"
BODY_TYPE"PLUMBING"
HDL_TAP"TRUE";
"B \NAC \NWC"7;
"S \NAC"
BN"1"57;
%"TAP"
"6","(-3700,5825)","2","mstr_standard","I152";
;
BOM_COST"IO_SLOT"
ROOM"RISER1"
CDS_LIB"mstr_standard"
BODY_TYPE"PLUMBING"
HDL_TAP"TRUE";
"B \NAC \NWC"7;
"S \NAC"
BN"0"59;
%"TAP"
"6","(-3850,5875)","2","mstr_standard","I153";
;
BOM_COST"IO_SLOT"
ROOM"RISER1"
CDS_LIB"mstr_standard"
BODY_TYPE"PLUMBING"
HDL_TAP"TRUE";
"B \NAC \NWC"8;
"S \NAC"
BN"0"62;
%"TAP"
"6","(-3850,5775)","2","mstr_standard","I154";
;
BOM_COST"IO_SLOT"
ROOM"RISER1"
CDS_LIB"mstr_standard"
BODY_TYPE"PLUMBING"
HDL_TAP"TRUE";
"B \NAC \NWC"8;
"S \NAC"
BN"1"61;
%"TAP"
"6","(-3700,5625)","2","standard","I155";
;
BOM_COST"IO_SLOT"
ROOM"RISER1"
CDS_LIB"standard"
BODY_TYPE"PLUMBING"
HDL_TAP"TRUE";
"B \NAC \NWC"7;
"S \NAC"
BN"2"56;
%"TAP"
"6","(-3700,5525)","2","standard","I156";
;
BOM_COST"IO_SLOT"
ROOM"RISER1"
CDS_LIB"standard"
BODY_TYPE"PLUMBING"
HDL_TAP"TRUE";
"B \NAC \NWC"7;
"S \NAC"
BN"3"54;
%"TAP"
"6","(-3850,5675)","2","standard","I157";
;
BOM_COST"IO_SLOT"
ROOM"RISER1"
CDS_LIB"standard"
BODY_TYPE"PLUMBING"
HDL_TAP"TRUE";
"B \NAC \NWC"8;
"S \NAC"
BN"2"60;
%"TAP"
"6","(-3850,5575)","2","standard","I158";
;
BOM_COST"IO_SLOT"
ROOM"RISER1"
CDS_LIB"standard"
BODY_TYPE"PLUMBING"
HDL_TAP"TRUE";
"B \NAC \NWC"8;
"S \NAC"
BN"3"58;
%"TAP"
"6","(-3850,5475)","2","standard","I159";
;
BOM_COST"IO_SLOT"
ROOM"RISER1"
CDS_LIB"standard"
BODY_TYPE"PLUMBING"
HDL_TAP"TRUE";
"B \NAC \NWC"8;
"S \NAC"
BN"4"12;
%"TAP"
"6","(-3700,5325)","2","standard","I160";
;
BOM_COST"IO_SLOT"
ROOM"RISER1"
CDS_LIB"standard"
BODY_TYPE"PLUMBING"
HDL_TAP"TRUE";
"B \NAC \NWC"7;
"S \NAC"
BN"5"51;
%"TAP"
"6","(-3700,5425)","2","standard","I161";
;
BOM_COST"IO_SLOT"
ROOM"RISER1"
CDS_LIB"standard"
BODY_TYPE"PLUMBING"
HDL_TAP"TRUE";
"B \NAC \NWC"7;
"S \NAC"
BN"4"11;
%"TAP"
"6","(-3700,5225)","2","standard","I162";
;
BOM_COST"IO_SLOT"
ROOM"RISER1"
CDS_LIB"standard"
BODY_TYPE"PLUMBING"
HDL_TAP"TRUE";
"B \NAC \NWC"7;
"S \NAC"
BN"6"50;
%"TAP"
"6","(-3850,5375)","2","standard","I163";
;
BOM_COST"IO_SLOT"
ROOM"RISER1"
CDS_LIB"standard"
BODY_TYPE"PLUMBING"
HDL_TAP"TRUE";
"B \NAC \NWC"8;
"S \NAC"
BN"5"55;
%"TAP"
"6","(-3850,5275)","2","standard","I164";
;
BOM_COST"IO_SLOT"
ROOM"RISER1"
CDS_LIB"standard"
BODY_TYPE"PLUMBING"
HDL_TAP"TRUE";
"B \NAC \NWC"8;
"S \NAC"
BN"6"53;
%"TAP"
"6","(-3700,5125)","2","standard","I165";
;
BOM_COST"IO_SLOT"
ROOM"RISER1"
CDS_LIB"standard"
BODY_TYPE"PLUMBING"
HDL_TAP"TRUE";
"B \NAC \NWC"7;
"S \NAC"
BN"7"49;
%"TAP"
"6","(-3700,5025)","2","standard","I166";
;
BOM_COST"IO_SLOT"
ROOM"RISER1"
CDS_LIB"standard"
BODY_TYPE"PLUMBING"
HDL_TAP"TRUE";
"B \NAC \NWC"7;
"S \NAC"
BN"8"76;
%"TAP"
"6","(-3850,5175)","2","standard","I167";
;
BOM_COST"IO_SLOT"
ROOM"RISER1"
CDS_LIB"standard"
BODY_TYPE"PLUMBING"
HDL_TAP"TRUE";
"B \NAC \NWC"8;
"S \NAC"
BN"7"52;
%"TAP"
"6","(-3850,5075)","2","standard","I168";
;
BOM_COST"IO_SLOT"
ROOM"RISER1"
CDS_LIB"standard"
BODY_TYPE"PLUMBING"
HDL_TAP"TRUE";
"B \NAC \NWC"8;
"S \NAC"
BN"8"77;
%"TAP"
"6","(-3850,4975)","2","standard","I169";
;
BOM_COST"IO_SLOT"
ROOM"RISER1"
CDS_LIB"standard"
BODY_TYPE"PLUMBING"
HDL_TAP"TRUE";
"B \NAC \NWC"8;
"S \NAC"
BN"9"75;
%"TAP"
"6","(-3700,4825)","2","standard","I170";
;
BOM_COST"IO_SLOT"
ROOM"RISER1"
CDS_LIB"standard"
BODY_TYPE"PLUMBING"
HDL_TAP"TRUE";
"B \NAC \NWC"7;
"S \NAC"
BN"10"72;
%"TAP"
"6","(-3700,4925)","2","standard","I171";
;
BOM_COST"IO_SLOT"
ROOM"RISER1"
CDS_LIB"standard"
BODY_TYPE"PLUMBING"
HDL_TAP"TRUE";
"B \NAC \NWC"7;
"S \NAC"
BN"9"74;
%"TAP"
"6","(-3700,4725)","2","standard","I172";
;
BOM_COST"IO_SLOT"
ROOM"RISER1"
CDS_LIB"standard"
BODY_TYPE"PLUMBING"
HDL_TAP"TRUE";
"B \NAC \NWC"7;
"S \NAC"
BN"11"70;
%"TAP"
"6","(-3850,4875)","2","standard","I173";
;
BOM_COST"IO_SLOT"
ROOM"RISER1"
CDS_LIB"standard"
BODY_TYPE"PLUMBING"
HDL_TAP"TRUE";
"B \NAC \NWC"8;
"S \NAC"
BN"10"73;
%"TAP"
"6","(-3850,4775)","2","standard","I174";
;
BOM_COST"IO_SLOT"
ROOM"RISER1"
CDS_LIB"standard"
BODY_TYPE"PLUMBING"
HDL_TAP"TRUE";
"B \NAC \NWC"8;
"S \NAC"
BN"11"71;
%"TAP"
"6","(-3700,4625)","2","standard","I175";
;
BOM_COST"IO_SLOT"
ROOM"RISER1"
CDS_LIB"standard"
BODY_TYPE"PLUMBING"
HDL_TAP"TRUE";
"B \NAC \NWC"7;
"S \NAC"
BN"12"68;
%"TAP"
"6","(-3700,4525)","2","standard","I176";
;
BOM_COST"IO_SLOT"
ROOM"RISER1"
CDS_LIB"standard"
BODY_TYPE"PLUMBING"
HDL_TAP"TRUE";
"B \NAC \NWC"7;
"S \NAC"
BN"13"66;
%"TAP"
"6","(-3850,4575)","2","standard","I177";
;
BOM_COST"IO_SLOT"
ROOM"RISER1"
CDS_LIB"standard"
BODY_TYPE"PLUMBING"
HDL_TAP"TRUE";
"B \NAC \NWC"8;
"S \NAC"
BN"13"67;
%"TAP"
"6","(-3850,4675)","2","standard","I178";
;
BOM_COST"IO_SLOT"
ROOM"RISER1"
CDS_LIB"standard"
BODY_TYPE"PLUMBING"
HDL_TAP"TRUE";
"B \NAC \NWC"8;
"S \NAC"
BN"12"69;
%"TAP"
"6","(-3850,4475)","2","standard","I179";
;
BOM_COST"IO_SLOT"
ROOM"RISER1"
CDS_LIB"standard"
BODY_TYPE"PLUMBING"
HDL_TAP"TRUE";
"B \NAC \NWC"8;
"S \NAC"
BN"14"65;
%"TAP"
"6","(-3700,4325)","2","standard","I180";
;
BOM_COST"IO_SLOT"
ROOM"RISER1"
CDS_LIB"standard"
BODY_TYPE"PLUMBING"
HDL_TAP"TRUE";
"B \NAC \NWC"7;
"S \NAC"
BN"15"78;
%"TAP"
"6","(-3700,4425)","2","standard","I181";
;
BOM_COST"IO_SLOT"
ROOM"RISER1"
CDS_LIB"standard"
BODY_TYPE"PLUMBING"
HDL_TAP"TRUE";
"B \NAC \NWC"7;
"S \NAC"
BN"14"64;
%"TAP"
"6","(-3850,4375)","2","standard","I182";
;
BOM_COST"IO_SLOT"
ROOM"RISER1"
CDS_LIB"standard"
BODY_TYPE"PLUMBING"
HDL_TAP"TRUE";
"B \NAC \NWC"8;
"S \NAC"
BN"15"63;
%"TAP"
"6","(-6300,5875)","0","mstr_standard","I325";
;
CDS_LIB"mstr_standard"
BODY_TYPE"PLUMBING"
HDL_TAP"TRUE";
"B \NAC \NWC"5;
"S \NAC"
BN"0"38;
%"TAP"
"6","(-6300,5675)","0","mstr_standard","I326";
;
CDS_LIB"mstr_standard"
BODY_TYPE"PLUMBING"
HDL_TAP"TRUE";
"B \NAC \NWC"5;
"S \NAC"
BN"2"36;
%"TAP"
"6","(-6300,5775)","0","mstr_standard","I327";
;
CDS_LIB"mstr_standard"
BODY_TYPE"PLUMBING"
HDL_TAP"TRUE";
"B \NAC \NWC"5;
"S \NAC"
BN"1"37;
%"TAP"
"6","(-6450,5825)","0","mstr_standard","I328";
;
CDS_LIB"mstr_standard"
BODY_TYPE"PLUMBING"
HDL_TAP"TRUE";
"B \NAC \NWC"6;
"S \NAC"
BN"0"35;
%"TAP"
"6","(-6450,5725)","0","mstr_standard","I329";
;
CDS_LIB"mstr_standard"
BODY_TYPE"PLUMBING"
HDL_TAP"TRUE";
"B \NAC \NWC"6;
"S \NAC"
BN"1"34;
%"TAP"
"6","(-6300,5575)","0","standard","I330";
;
CDS_LIB"standard"
BODY_TYPE"PLUMBING"
HDL_TAP"TRUE";
"B \NAC \NWC"5;
"S \NAC"
BN"3"10;
%"TAP"
"6","(-6300,5475)","0","standard","I331";
;
CDS_LIB"standard"
BODY_TYPE"PLUMBING"
HDL_TAP"TRUE";
"B \NAC \NWC"5;
"S \NAC"
BN"4"33;
%"TAP"
"6","(-6300,5275)","0","standard","I332";
;
CDS_LIB"standard"
BODY_TYPE"PLUMBING"
HDL_TAP"TRUE";
"B \NAC \NWC"5;
"S \NAC"
BN"6"30;
%"TAP"
"6","(-6300,5375)","0","standard","I333";
;
CDS_LIB"standard"
BODY_TYPE"PLUMBING"
HDL_TAP"TRUE";
"B \NAC \NWC"5;
"S \NAC"
BN"5"32;
%"TAP"
"6","(-6300,5175)","0","standard","I334";
;
CDS_LIB"standard"
BODY_TYPE"PLUMBING"
HDL_TAP"TRUE";
"B \NAC \NWC"5;
"S \NAC"
BN"7"28;
%"TAP"
"6","(-6450,5525)","0","standard","I335";
;
CDS_LIB"standard"
BODY_TYPE"PLUMBING"
HDL_TAP"TRUE";
"B \NAC \NWC"6;
"S \NAC"
BN"3"31;
%"TAP"
"6","(-6450,5425)","0","standard","I336";
;
CDS_LIB"standard"
BODY_TYPE"PLUMBING"
HDL_TAP"TRUE";
"B \NAC \NWC"6;
"S \NAC"
BN"4"29;
%"TAP"
"6","(-6450,5625)","0","standard","I337";
;
CDS_LIB"standard"
BODY_TYPE"PLUMBING"
HDL_TAP"TRUE";
"B \NAC \NWC"6;
"S \NAC"
BN"2"9;
%"TAP"
"6","(-6450,5325)","0","standard","I338";
;
CDS_LIB"standard"
BODY_TYPE"PLUMBING"
HDL_TAP"TRUE";
"B \NAC \NWC"6;
"S \NAC"
BN"5"27;
%"TAP"
"6","(-6450,5225)","0","standard","I339";
;
CDS_LIB"standard"
BODY_TYPE"PLUMBING"
HDL_TAP"TRUE";
"B \NAC \NWC"6;
"S \NAC"
BN"6"26;
%"TAP"
"6","(-6300,5075)","0","standard","I340";
;
CDS_LIB"standard"
BODY_TYPE"PLUMBING"
HDL_TAP"TRUE";
"B \NAC \NWC"5;
"S \NAC"
BN"8"48;
%"TAP"
"6","(-6300,4975)","0","standard","I341";
;
CDS_LIB"standard"
BODY_TYPE"PLUMBING"
HDL_TAP"TRUE";
"B \NAC \NWC"5;
"S \NAC"
BN"9"46;
%"TAP"
"6","(-6300,4875)","0","standard","I342";
;
CDS_LIB"standard"
BODY_TYPE"PLUMBING"
HDL_TAP"TRUE";
"B \NAC \NWC"5;
"S \NAC"
BN"10"44;
%"TAP"
"6","(-6300,4775)","0","standard","I343";
;
CDS_LIB"standard"
BODY_TYPE"PLUMBING"
HDL_TAP"TRUE";
"B \NAC \NWC"5;
"S \NAC"
BN"11"42;
%"TAP"
"6","(-6300,4675)","0","standard","I344";
;
CDS_LIB"standard"
BODY_TYPE"PLUMBING"
HDL_TAP"TRUE";
"B \NAC \NWC"5;
"S \NAC"
BN"12"40;
%"TAP"
"6","(-6450,5125)","0","standard","I345";
;
CDS_LIB"standard"
BODY_TYPE"PLUMBING"
HDL_TAP"TRUE";
"B \NAC \NWC"6;
"S \NAC"
BN"7"25;
%"TAP"
"6","(-6450,4925)","0","standard","I346";
;
CDS_LIB"standard"
BODY_TYPE"PLUMBING"
HDL_TAP"TRUE";
"B \NAC \NWC"6;
"S \NAC"
BN"9"45;
%"TAP"
"6","(-6450,5025)","0","standard","I347";
;
CDS_LIB"standard"
BODY_TYPE"PLUMBING"
HDL_TAP"TRUE";
"B \NAC \NWC"6;
"S \NAC"
BN"8"47;
%"TAP"
"6","(-6450,4825)","0","standard","I348";
;
CDS_LIB"standard"
BODY_TYPE"PLUMBING"
HDL_TAP"TRUE";
"B \NAC \NWC"6;
"S \NAC"
BN"10"43;
%"TAP"
"6","(-6450,4725)","0","standard","I349";
;
CDS_LIB"standard"
BODY_TYPE"PLUMBING"
HDL_TAP"TRUE";
"B \NAC \NWC"6;
"S \NAC"
BN"11"41;
%"TAP"
"6","(-6300,4575)","0","standard","I350";
;
CDS_LIB"standard"
BODY_TYPE"PLUMBING"
HDL_TAP"TRUE";
"B \NAC \NWC"5;
"S \NAC"
BN"13"23;
%"TAP"
"6","(-6300,4475)","0","standard","I351";
;
CDS_LIB"standard"
BODY_TYPE"PLUMBING"
HDL_TAP"TRUE";
"B \NAC \NWC"5;
"S \NAC"
BN"14"80;
%"TAP"
"6","(-6300,4375)","0","standard","I352";
;
CDS_LIB"standard"
BODY_TYPE"PLUMBING"
HDL_TAP"TRUE";
"B \NAC \NWC"5;
"S \NAC"
BN"15"124;
%"TAP"
"6","(-6450,4625)","0","standard","I353";
;
CDS_LIB"standard"
BODY_TYPE"PLUMBING"
HDL_TAP"TRUE";
"B \NAC \NWC"6;
"S \NAC"
BN"12"24;
%"TAP"
"6","(-6450,4425)","0","standard","I354";
;
CDS_LIB"standard"
BODY_TYPE"PLUMBING"
HDL_TAP"TRUE";
"B \NAC \NWC"6;
"S \NAC"
BN"14"39;
%"TAP"
"6","(-6450,4525)","0","standard","I355";
;
CDS_LIB"standard"
BODY_TYPE"PLUMBING"
HDL_TAP"TRUE";
"B \NAC \NWC"6;
"S \NAC"
BN"13"22;
%"TAP"
"6","(-6450,4325)","0","standard","I356";
;
CDS_LIB"standard"
BODY_TYPE"PLUMBING"
HDL_TAP"TRUE";
"B \NAC \NWC"6;
"S \NAC"
BN"15"79;
%"TAP"
"6","(-6300,2950)","0","mstr_standard","I359";
;
CDS_LIB"mstr_standard"
BODY_TYPE"PLUMBING"
HDL_TAP"TRUE";
"B \NAC \NWC"3;
"S \NAC"
BN"1"134;
%"TAP"
"6","(-6300,3050)","0","mstr_standard","I360";
;
CDS_LIB"mstr_standard"
BODY_TYPE"PLUMBING"
HDL_TAP"TRUE";
"B \NAC \NWC"3;
"S \NAC"
BN"0"100;
%"TAP"
"6","(-6300,2850)","0","mstr_standard","I361";
;
CDS_LIB"mstr_standard"
BODY_TYPE"PLUMBING"
HDL_TAP"TRUE";
"B \NAC \NWC"3;
"S \NAC"
BN"2"21;
%"TAP"
"6","(-6450,3000)","0","mstr_standard","I362";
;
CDS_LIB"mstr_standard"
BODY_TYPE"PLUMBING"
HDL_TAP"TRUE";
"B \NAC \NWC"4;
"S \NAC"
BN"0"133;
%"TAP"
"6","(-6450,2900)","0","mstr_standard","I363";
;
CDS_LIB"mstr_standard"
BODY_TYPE"PLUMBING"
HDL_TAP"TRUE";
"B \NAC \NWC"4;
"S \NAC"
BN"1"99;
%"TAP"
"6","(-6300,2750)","0","standard","I364";
;
CDS_LIB"standard"
BODY_TYPE"PLUMBING"
HDL_TAP"TRUE";
"B \NAC \NWC"3;
"S \NAC"
BN"3"20;
%"TAP"
"6","(-6300,2650)","0","standard","I365";
;
CDS_LIB"standard"
BODY_TYPE"PLUMBING"
HDL_TAP"TRUE";
"B \NAC \NWC"3;
"S \NAC"
BN"4"102;
%"TAP"
"6","(-6300,2550)","0","standard","I366";
;
CDS_LIB"standard"
BODY_TYPE"PLUMBING"
HDL_TAP"TRUE";
"B \NAC \NWC"3;
"S \NAC"
BN"5"98;
%"TAP"
"6","(-6300,2450)","0","standard","I367";
;
CDS_LIB"standard"
BODY_TYPE"PLUMBING"
HDL_TAP"TRUE";
"B \NAC \NWC"3;
"S \NAC"
BN"6"96;
%"TAP"
"6","(-6300,2350)","0","standard","I368";
;
CDS_LIB"standard"
BODY_TYPE"PLUMBING"
HDL_TAP"TRUE";
"B \NAC \NWC"3;
"S \NAC"
BN"7"104;
%"TAP"
"6","(-6450,2700)","0","standard","I369";
;
CDS_LIB"standard"
BODY_TYPE"PLUMBING"
HDL_TAP"TRUE";
"B \NAC \NWC"4;
"S \NAC"
BN"3"123;
%"TAP"
"6","(-6450,2800)","0","standard","I370";
;
CDS_LIB"standard"
BODY_TYPE"PLUMBING"
HDL_TAP"TRUE";
"B \NAC \NWC"4;
"S \NAC"
BN"2"19;
%"TAP"
"6","(-6450,2600)","0","standard","I371";
;
CDS_LIB"standard"
BODY_TYPE"PLUMBING"
HDL_TAP"TRUE";
"B \NAC \NWC"4;
"S \NAC"
BN"4"101;
%"TAP"
"6","(-6450,2500)","0","standard","I372";
;
CDS_LIB"standard"
BODY_TYPE"PLUMBING"
HDL_TAP"TRUE";
"B \NAC \NWC"4;
"S \NAC"
BN"5"97;
%"TAP"
"6","(-6450,2400)","0","standard","I373";
;
CDS_LIB"standard"
BODY_TYPE"PLUMBING"
HDL_TAP"TRUE";
"B \NAC \NWC"4;
"S \NAC"
BN"6"103;
%"TAP"
"6","(-6450,2300)","0","standard","I374";
;
CDS_LIB"standard"
BODY_TYPE"PLUMBING"
HDL_TAP"TRUE";
"B \NAC \NWC"4;
"S \NAC"
BN"7"95;
%"TAP"
"6","(-6300,2250)","0","standard","I375";
;
CDS_LIB"standard"
BODY_TYPE"PLUMBING"
HDL_TAP"TRUE";
"B \NAC \NWC"3;
"S \NAC"
BN"8"94;
%"TAP"
"6","(-6300,2150)","0","standard","I376";
;
CDS_LIB"standard"
BODY_TYPE"PLUMBING"
HDL_TAP"TRUE";
"B \NAC \NWC"3;
"S \NAC"
BN"9"93;
%"TAP"
"6","(-6300,2050)","0","standard","I377";
;
CDS_LIB"standard"
BODY_TYPE"PLUMBING"
HDL_TAP"TRUE";
"B \NAC \NWC"3;
"S \NAC"
BN"10"92;
%"TAP"
"6","(-6300,1950)","0","standard","I378";
;
CDS_LIB"standard"
BODY_TYPE"PLUMBING"
HDL_TAP"TRUE";
"B \NAC \NWC"3;
"S \NAC"
BN"11"111;
%"TAP"
"6","(-6300,1850)","0","standard","I379";
;
CDS_LIB"standard"
BODY_TYPE"PLUMBING"
HDL_TAP"TRUE";
"B \NAC \NWC"3;
"S \NAC"
BN"12"91;
%"TAP"
"6","(-6450,2200)","0","standard","I380";
;
CDS_LIB"standard"
BODY_TYPE"PLUMBING"
HDL_TAP"TRUE";
"B \NAC \NWC"4;
"S \NAC"
BN"8"105;
%"TAP"
"6","(-6450,2100)","0","standard","I381";
;
CDS_LIB"standard"
BODY_TYPE"PLUMBING"
HDL_TAP"TRUE";
"B \NAC \NWC"4;
"S \NAC"
BN"9"106;
%"TAP"
"6","(-6450,2000)","0","standard","I382";
;
CDS_LIB"standard"
BODY_TYPE"PLUMBING"
HDL_TAP"TRUE";
"B \NAC \NWC"4;
"S \NAC"
BN"10"107;
%"TAP"
"6","(-6450,1900)","0","standard","I383";
;
CDS_LIB"standard"
BODY_TYPE"PLUMBING"
HDL_TAP"TRUE";
"B \NAC \NWC"4;
"S \NAC"
BN"11"108;
%"TAP"
"6","(-6450,1800)","0","standard","I384";
;
CDS_LIB"standard"
BODY_TYPE"PLUMBING"
HDL_TAP"TRUE";
"B \NAC \NWC"4;
"S \NAC"
BN"12"112;
%"TAP"
"6","(-6300,1750)","0","standard","I385";
;
CDS_LIB"standard"
BODY_TYPE"PLUMBING"
HDL_TAP"TRUE";
"B \NAC \NWC"3;
"S \NAC"
BN"13"90;
%"TAP"
"6","(-6300,1550)","0","standard","I386";
;
CDS_LIB"standard"
BODY_TYPE"PLUMBING"
HDL_TAP"TRUE";
"B \NAC \NWC"3;
"S \NAC"
BN"15"87;
%"TAP"
"6","(-6300,1650)","0","standard","I387";
;
CDS_LIB"standard"
BODY_TYPE"PLUMBING"
HDL_TAP"TRUE";
"B \NAC \NWC"3;
"S \NAC"
BN"14"88;
%"TAP"
"6","(-6450,1700)","0","standard","I388";
;
CDS_LIB"standard"
BODY_TYPE"PLUMBING"
HDL_TAP"TRUE";
"B \NAC \NWC"4;
"S \NAC"
BN"13"89;
%"TAP"
"6","(-6450,1600)","0","standard","I389";
;
CDS_LIB"standard"
BODY_TYPE"PLUMBING"
HDL_TAP"TRUE";
"B \NAC \NWC"4;
"S \NAC"
BN"14"113;
%"TAP"
"6","(-6450,1500)","0","standard","I390";
;
CDS_LIB"standard"
BODY_TYPE"PLUMBING"
HDL_TAP"TRUE";
"B \NAC \NWC"4;
"S \NAC"
BN"15"86;
%"TAP"
"6","(-3700,3000)","2","mstr_standard","I393";
;
CDS_LIB"mstr_standard"
BOM_COST"IO_SLOT"
ROOM"RISER1"
BODY_TYPE"PLUMBING"
HDL_TAP"TRUE";
"B \NAC \NWC"1;
"S \NAC"
BN"0"18;
%"TAP"
"6","(-3700,2900)","2","mstr_standard","I394";
;
CDS_LIB"mstr_standard"
BOM_COST"IO_SLOT"
ROOM"RISER1"
BODY_TYPE"PLUMBING"
HDL_TAP"TRUE";
"B \NAC \NWC"1;
"S \NAC"
BN"1"128;
%"TAP"
"6","(-3850,2950)","2","mstr_standard","I395";
;
CDS_LIB"mstr_standard"
BOM_COST"IO_SLOT"
ROOM"RISER1"
BODY_TYPE"PLUMBING"
HDL_TAP"TRUE";
"B \NAC \NWC"2;
"S \NAC"
BN"1"17;
%"TAP"
"6","(-3850,3050)","2","mstr_standard","I396";
;
CDS_LIB"mstr_standard"
BOM_COST"IO_SLOT"
ROOM"RISER1"
BODY_TYPE"PLUMBING"
HDL_TAP"TRUE";
"B \NAC \NWC"2;
"S \NAC"
BN"0"127;
%"TAP"
"6","(-3850,2850)","2","standard","I397";
;
CDS_LIB"standard"
BOM_COST"IO_SLOT"
ROOM"RISER1"
BODY_TYPE"PLUMBING"
HDL_TAP"TRUE";
"B \NAC \NWC"2;
"S \NAC"
BN"2"135;
%"TAP"
"6","(-3700,2700)","2","standard","I398";
;
CDS_LIB"standard"
BOM_COST"IO_SLOT"
ROOM"RISER1"
BODY_TYPE"PLUMBING"
HDL_TAP"TRUE";
"B \NAC \NWC"1;
"S \NAC"
BN"3"130;
%"TAP"
"6","(-3700,2800)","2","standard","I399";
;
CDS_LIB"standard"
BOM_COST"IO_SLOT"
ROOM"RISER1"
BODY_TYPE"PLUMBING"
HDL_TAP"TRUE";
"B \NAC \NWC"1;
"S \NAC"
BN"2"136;
%"TAP"
"6","(-3700,2600)","2","standard","I400";
;
CDS_LIB"standard"
BOM_COST"IO_SLOT"
ROOM"RISER1"
BODY_TYPE"PLUMBING"
HDL_TAP"TRUE";
"B \NAC \NWC"1;
"S \NAC"
BN"4"132;
%"TAP"
"6","(-3700,2500)","2","standard","I401";
;
CDS_LIB"standard"
ROOM"RISER1"
BOM_COST"IO_SLOT"
BODY_TYPE"PLUMBING"
HDL_TAP"TRUE";
"B \NAC \NWC"1;
"S \NAC"
BN"5"84;
%"TAP"
"6","(-3700,2300)","2","standard","I402";
;
CDS_LIB"standard"
ROOM"RISER1"
BOM_COST"IO_SLOT"
BODY_TYPE"PLUMBING"
HDL_TAP"TRUE";
"B \NAC \NWC"1;
"S \NAC"
BN"7"16;
%"TAP"
"6","(-3700,2400)","2","standard","I403";
;
CDS_LIB"standard"
ROOM"RISER1"
BOM_COST"IO_SLOT"
BODY_TYPE"PLUMBING"
HDL_TAP"TRUE";
"B \NAC \NWC"1;
"S \NAC"
BN"6"121;
%"TAP"
"6","(-3850,2750)","2","standard","I404";
;
CDS_LIB"standard"
BOM_COST"IO_SLOT"
ROOM"RISER1"
BODY_TYPE"PLUMBING"
HDL_TAP"TRUE";
"B \NAC \NWC"2;
"S \NAC"
BN"3"129;
%"TAP"
"6","(-3850,2650)","2","standard","I405";
;
CDS_LIB"standard"
BOM_COST"IO_SLOT"
ROOM"RISER1"
BODY_TYPE"PLUMBING"
HDL_TAP"TRUE";
"B \NAC \NWC"2;
"S \NAC"
BN"4"131;
%"TAP"
"6","(-3850,2450)","2","standard","I406";
;
CDS_LIB"standard"
ROOM"RISER1"
BOM_COST"IO_SLOT"
BODY_TYPE"PLUMBING"
HDL_TAP"TRUE";
"B \NAC \NWC"2;
"S \NAC"
BN"6"122;
%"TAP"
"6","(-3850,2550)","2","standard","I407";
;
CDS_LIB"standard"
ROOM"RISER1"
BOM_COST"IO_SLOT"
BODY_TYPE"PLUMBING"
HDL_TAP"TRUE";
"B \NAC \NWC"2;
"S \NAC"
BN"5"85;
%"TAP"
"6","(-3850,2350)","2","standard","I408";
;
CDS_LIB"standard"
ROOM"RISER1"
BOM_COST"IO_SLOT"
BODY_TYPE"PLUMBING"
HDL_TAP"TRUE";
"B \NAC \NWC"2;
"S \NAC"
BN"7"126;
%"TAP"
"6","(-3700,2100)","2","standard","I409";
;
CDS_LIB"standard"
ROOM"RISER1"
BOM_COST"IO_SLOT"
BODY_TYPE"PLUMBING"
HDL_TAP"TRUE";
"B \NAC \NWC"1;
"S \NAC"
BN"9"13;
%"TAP"
"6","(-3700,2200)","2","standard","I410";
;
CDS_LIB"standard"
ROOM"RISER1"
BOM_COST"IO_SLOT"
BODY_TYPE"PLUMBING"
HDL_TAP"TRUE";
"B \NAC \NWC"1;
"S \NAC"
BN"8"15;
%"TAP"
"6","(-3700,2000)","2","standard","I411";
;
CDS_LIB"standard"
ROOM"RISER1"
BOM_COST"IO_SLOT"
BODY_TYPE"PLUMBING"
HDL_TAP"TRUE";
"B \NAC \NWC"1;
"S \NAC"
BN"10"110;
%"TAP"
"6","(-3700,1800)","2","standard","I412";
;
CDS_LIB"standard"
ROOM"RISER1"
BOM_COST"IO_SLOT"
BODY_TYPE"PLUMBING"
HDL_TAP"TRUE";
"B \NAC \NWC"1;
"S \NAC"
BN"12"120;
%"TAP"
"6","(-3700,1900)","2","standard","I413";
;
CDS_LIB"standard"
ROOM"RISER1"
BOM_COST"IO_SLOT"
BODY_TYPE"PLUMBING"
HDL_TAP"TRUE";
"B \NAC \NWC"1;
"S \NAC"
BN"11"81;
%"TAP"
"6","(-3850,2250)","2","standard","I414";
;
CDS_LIB"standard"
ROOM"RISER1"
BOM_COST"IO_SLOT"
BODY_TYPE"PLUMBING"
HDL_TAP"TRUE";
"B \NAC \NWC"2;
"S \NAC"
BN"8"125;
%"TAP"
"6","(-3850,2050)","2","standard","I415";
;
CDS_LIB"standard"
ROOM"RISER1"
BOM_COST"IO_SLOT"
BODY_TYPE"PLUMBING"
HDL_TAP"TRUE";
"B \NAC \NWC"2;
"S \NAC"
BN"10"83;
%"TAP"
"6","(-3850,2150)","2","standard","I416";
;
CDS_LIB"standard"
ROOM"RISER1"
BOM_COST"IO_SLOT"
BODY_TYPE"PLUMBING"
HDL_TAP"TRUE";
"B \NAC \NWC"2;
"S \NAC"
BN"9"14;
%"TAP"
"6","(-3850,1950)","2","standard","I417";
;
CDS_LIB"standard"
ROOM"RISER1"
BOM_COST"IO_SLOT"
BODY_TYPE"PLUMBING"
HDL_TAP"TRUE";
"B \NAC \NWC"2;
"S \NAC"
BN"11"82;
%"TAP"
"6","(-3850,1850)","2","standard","I418";
;
CDS_LIB"standard"
ROOM"RISER1"
BOM_COST"IO_SLOT"
BODY_TYPE"PLUMBING"
HDL_TAP"TRUE";
"B \NAC \NWC"2;
"S \NAC"
BN"12"109;
%"TAP"
"6","(-3700,1600)","2","standard","I419";
;
CDS_LIB"standard"
ROOM"RISER1"
BOM_COST"IO_SLOT"
BODY_TYPE"PLUMBING"
HDL_TAP"TRUE";
"B \NAC \NWC"1;
"S \NAC"
BN"14"116;
%"TAP"
"6","(-3700,1700)","2","standard","I420";
;
CDS_LIB"standard"
ROOM"RISER1"
BOM_COST"IO_SLOT"
BODY_TYPE"PLUMBING"
HDL_TAP"TRUE";
"B \NAC \NWC"1;
"S \NAC"
BN"13"118;
%"TAP"
"6","(-3700,1500)","2","standard","I421";
;
CDS_LIB"standard"
ROOM"RISER1"
BOM_COST"IO_SLOT"
BODY_TYPE"PLUMBING"
HDL_TAP"TRUE";
"B \NAC \NWC"1;
"S \NAC"
BN"15"114;
%"TAP"
"6","(-3850,1750)","2","standard","I422";
;
CDS_LIB"standard"
ROOM"RISER1"
BOM_COST"IO_SLOT"
BODY_TYPE"PLUMBING"
HDL_TAP"TRUE";
"B \NAC \NWC"2;
"S \NAC"
BN"13"119;
%"TAP"
"6","(-3850,1550)","2","standard","I423";
;
CDS_LIB"standard"
ROOM"RISER1"
BOM_COST"IO_SLOT"
BODY_TYPE"PLUMBING"
HDL_TAP"TRUE";
"B \NAC \NWC"2;
"S \NAC"
BN"15"115;
%"TAP"
"6","(-3850,1650)","2","standard","I424";
;
CDS_LIB"standard"
ROOM"RISER1"
BOM_COST"IO_SLOT"
BODY_TYPE"PLUMBING"
HDL_TAP"TRUE";
"B \NAC \NWC"2;
"S \NAC"
BN"14"117;
END.
